(kicad_pcb
	(version 20241229)
	(generator "pcbnew")
	(generator_version "9.0")
	(general
		(thickness 1.599998)
		(legacy_teardrops no)
	)
	(paper "A4")
	(title_block
		(title "Artix - Datacenter Secure Control Module (DC-SCM)")
		(date "2024-11-06")
		(rev "1.1.3")
		(comment 9 "footprints 419-424 of 544")
	)
	(layers
		(0 "F.Cu" signal)
		(4 "In1.Cu" signal)
		(6 "In2.Cu" signal)
		(8 "In3.Cu" signal)
		(10 "In4.Cu" signal)
		(12 "In5.Cu" signal)
		(14 "In6.Cu" signal)
		(2 "B.Cu" signal)
		(9 "F.Adhes" user "F.Adhesive")
		(11 "B.Adhes" user "B.Adhesive")
		(13 "F.Paste" user)
		(15 "B.Paste" user)
		(5 "F.SilkS" user "F.Silkscreen")
		(7 "B.SilkS" user "B.Silkscreen")
		(1 "F.Mask" user)
		(3 "B.Mask" user)
		(17 "Dwgs.User" user "User.Drawings")
		(19 "Cmts.User" user "User.Comments")
		(21 "Eco1.User" user "User.Eco1")
		(23 "Eco2.User" user "User.Eco2")
		(25 "Edge.Cuts" user)
		(27 "Margin" user)
		(31 "F.CrtYd" user "F.Courtyard")
		(29 "B.CrtYd" user "B.Courtyard")
		(35 "F.Fab" user)
		(33 "B.Fab" user)
	)
	(footprint "antmicro-footprints:R_0402_1005Metric"
		(layer "B.Cu")
		(at 71.24 149.925)
		(descr "Resistor SMD 0402")
		(tags "resistor SMD 0402")
		(property "Reference" "R36"
			(at -2.95 0.425 0)
			(layer "B.SilkS")
			(effects
				(font
					(size 0.7 0.7)
					(thickness 0.15)
				)
				(justify right bottom mirror)
			)
		)
		(property "Value" "R_10k_0402"
			(at 0 -1.4 0)
			(layer "B.Fab")
			(effects
				(font
					(size 0.7 0.7)
					(thickness 0.15)
				)
				(justify right bottom mirror)
			)
		)
		(property "Datasheet" "https://www.bourns.com/docs/product-datasheets/cr.pdf"
			(at 0 0 0)
			(layer "F.Fab")
			(hide yes)
			(effects
				(font
					(size 1.27 1.27)
					(thickness 0.15)
				)
			)
		)
		(property "Description" "SMD Chip Resistor, 10 kohm, ± 1%, 62.5 mW, 0402 [1005 Metric], Thick Film, General Purpose"
			(at 0 0 0)
			(layer "F.Fab")
			(hide yes)
			(effects
				(font
					(size 1.27 1.27)
					(thickness 0.15)
				)
			)
		)
		(property "Author" "Antmicro"
			(at 0 0 0)
			(layer "B.Fab")
			(hide yes)
			(effects
				(font
					(size 1 1)
					(thickness 0.15)
				)
				(justify mirror)
			)
		)
		(property "License" "Apache-2.0"
			(at 0 0 0)
			(layer "B.Fab")
			(hide yes)
			(effects
				(font
					(size 1 1)
					(thickness 0.15)
				)
				(justify mirror)
			)
		)
		(property "MPN" "CR0402-FX-1002GLF"
			(at 0 0 0)
			(layer "B.Fab")
			(hide yes)
			(effects
				(font
					(size 1 1)
					(thickness 0.15)
				)
				(justify mirror)
			)
		)
		(property "Manufacturer" "Bourns"
			(at 0 0 0)
			(layer "B.Fab")
			(hide yes)
			(effects
				(font
					(size 1 1)
					(thickness 0.15)
				)
				(justify mirror)
			)
		)
		(property "Tolerance" "1%"
			(at 0 0 0)
			(layer "B.Fab")
			(hide yes)
			(effects
				(font
					(size 1 1)
					(thickness 0.15)
				)
				(justify mirror)
			)
		)
		(property "Val" "10k"
			(at 0 0 0)
			(layer "B.Fab")
			(hide yes)
			(effects
				(font
					(size 1 1)
					(thickness 0.15)
				)
				(justify mirror)
			)
		)
		(sheetname "/RoT/")
		(sheetfile "rot.kicad_sch")
		(attr smd)
		(fp_rect
			(start -0.925 0.47)
			(end 0.925 -0.47)
			(stroke
				(width 0.05)
				(type default)
			)
			(fill no)
			(layer "B.CrtYd")
		)
		(fp_rect
			(start -0.5 0.25)
			(end 0.5 -0.25)
			(stroke
				(width 0.15)
				(type solid)
			)
			(fill no)
			(layer "B.Fab")
		)
		(pad "1" smd roundrect
			(at -0.48 0)
			(size 0.59 0.64)
			(layers "B.Cu" "B.Mask" "B.Paste")
			(roundrect_rratio 0.25)
			(net 133 "QSPIA1_D2")
			(pintype "passive")
		)
		(pad "2" smd roundrect
			(at 0.48 0)
			(size 0.59 0.64)
			(layers "B.Cu" "B.Mask" "B.Paste")
			(roundrect_rratio 0.25)
			(net 2 "VCC3V3")
			(pintype "passive")
		)
	)
	(footprint "antmicro-footprints:R_0402_1005Metric"
		(layer "B.Cu")
		(at 71.15 130.675)
		(descr "Resistor SMD 0402")
		(tags "resistor SMD 0402")
		(property "Reference" "R34"
			(at -2.95 0.425 0)
			(layer "B.SilkS")
			(effects
				(font
					(size 0.7 0.7)
					(thickness 0.15)
				)
				(justify right bottom mirror)
			)
		)
		(property "Value" "R_10k_0402"
			(at 0 -1.4 0)
			(layer "B.Fab")
			(effects
				(font
					(size 0.7 0.7)
					(thickness 0.15)
				)
				(justify right bottom mirror)
			)
		)
		(property "Datasheet" "https://www.bourns.com/docs/product-datasheets/cr.pdf"
			(at 0 0 0)
			(layer "F.Fab")
			(hide yes)
			(effects
				(font
					(size 1.27 1.27)
					(thickness 0.15)
				)
			)
		)
		(property "Description" "SMD Chip Resistor, 10 kohm, ± 1%, 62.5 mW, 0402 [1005 Metric], Thick Film, General Purpose"
			(at 0 0 0)
			(layer "F.Fab")
			(hide yes)
			(effects
				(font
					(size 1.27 1.27)
					(thickness 0.15)
				)
			)
		)
		(property "Author" "Antmicro"
			(at 0 0 0)
			(layer "B.Fab")
			(hide yes)
			(effects
				(font
					(size 1 1)
					(thickness 0.15)
				)
				(justify mirror)
			)
		)
		(property "License" "Apache-2.0"
			(at 0 0 0)
			(layer "B.Fab")
			(hide yes)
			(effects
				(font
					(size 1 1)
					(thickness 0.15)
				)
				(justify mirror)
			)
		)
		(property "MPN" "CR0402-FX-1002GLF"
			(at 0 0 0)
			(layer "B.Fab")
			(hide yes)
			(effects
				(font
					(size 1 1)
					(thickness 0.15)
				)
				(justify mirror)
			)
		)
		(property "Manufacturer" "Bourns"
			(at 0 0 0)
			(layer "B.Fab")
			(hide yes)
			(effects
				(font
					(size 1 1)
					(thickness 0.15)
				)
				(justify mirror)
			)
		)
		(property "Tolerance" "1%"
			(at 0 0 0)
			(layer "B.Fab")
			(hide yes)
			(effects
				(font
					(size 1 1)
					(thickness 0.15)
				)
				(justify mirror)
			)
		)
		(property "Val" "10k"
			(at 0 0 0)
			(layer "B.Fab")
			(hide yes)
			(effects
				(font
					(size 1 1)
					(thickness 0.15)
				)
				(justify mirror)
			)
		)
		(sheetname "/RoT/")
		(sheetfile "rot.kicad_sch")
		(attr smd)
		(fp_rect
			(start -0.925 0.47)
			(end 0.925 -0.47)
			(stroke
				(width 0.05)
				(type default)
			)
			(fill no)
			(layer "B.CrtYd")
		)
		(fp_rect
			(start -0.5 0.25)
			(end 0.5 -0.25)
			(stroke
				(width 0.15)
				(type solid)
			)
			(fill no)
			(layer "B.Fab")
		)
		(pad "1" smd roundrect
			(at -0.48 0)
			(size 0.59 0.64)
			(layers "B.Cu" "B.Mask" "B.Paste")
			(roundrect_rratio 0.25)
			(net 122 "QSPIB1_D2")
			(pintype "passive")
		)
		(pad "2" smd roundrect
			(at 0.48 0)
			(size 0.59 0.64)
			(layers "B.Cu" "B.Mask" "B.Paste")
			(roundrect_rratio 0.25)
			(net 2 "VCC3V3")
			(pintype "passive")
		)
	)
	(footprint "antmicro-footprints:C_0402_1005Metric"
		(layer "B.Cu")
		(at 98.075 146.375 90)
		(descr "Capacitor SMD 0402")
		(tags "capacitor SMD 0402")
		(property "Reference" "C155"
			(at 1.275 -8.675 90)
			(layer "B.SilkS")
			(effects
				(font
					(size 0.7 0.7)
					(thickness 0.15)
				)
				(justify right bottom mirror)
			)
		)
		(property "Value" "C_10u_0402"
			(at 0 -1.4 90)
			(layer "B.Fab")
			(effects
				(font
					(size 0.7 0.7)
					(thickness 0.15)
				)
				(justify right bottom mirror)
			)
		)
		(property "Datasheet" "https://www.yageo.com/en/Chart/Download/pdf/CC0402MRX5R5BB106"
			(at 0 0 90)
			(layer "F.Fab")
			(hide yes)
			(effects
				(font
					(size 1.27 1.27)
					(thickness 0.15)
				)
			)
		)
		(property "Description" "SMD Multilayer Ceramic Capacitor, 10 µF, 6.3 V, 0402 [1005 Metric], ± 20%, X5R, CC Series"
			(at 0 0 90)
			(layer "F.Fab")
			(hide yes)
			(effects
				(font
					(size 1.27 1.27)
					(thickness 0.15)
				)
			)
		)
		(property "Author" "Antmicro"
			(at 244.45 48.3 0)
			(layer "B.Fab")
			(hide yes)
			(effects
				(font
					(size 1 1)
					(thickness 0.15)
				)
				(justify mirror)
			)
		)
		(property "Dielectric" ""
			(at 244.45 48.3 0)
			(layer "B.Fab")
			(hide yes)
			(effects
				(font
					(size 1 1)
					(thickness 0.15)
				)
				(justify mirror)
			)
		)
		(property "License" "Apache-2.0"
			(at 244.45 48.3 0)
			(layer "B.Fab")
			(hide yes)
			(effects
				(font
					(size 1 1)
					(thickness 0.15)
				)
				(justify mirror)
			)
		)
		(property "MPN" "CC0402MRX5R5BB106"
			(at 244.45 48.3 0)
			(layer "B.Fab")
			(hide yes)
			(effects
				(font
					(size 1 1)
					(thickness 0.15)
				)
				(justify mirror)
			)
		)
		(property "Manufacturer" "YAGEO"
			(at 244.45 48.3 0)
			(layer "B.Fab")
			(hide yes)
			(effects
				(font
					(size 1 1)
					(thickness 0.15)
				)
				(justify mirror)
			)
		)
		(property "Val" "10u"
			(at 244.45 48.3 0)
			(layer "B.Fab")
			(hide yes)
			(effects
				(font
					(size 1 1)
					(thickness 0.15)
				)
				(justify mirror)
			)
		)
		(property "Voltage" ""
			(at 244.45 48.3 0)
			(layer "B.Fab")
			(hide yes)
			(effects
				(font
					(size 1 1)
					(thickness 0.15)
				)
				(justify mirror)
			)
		)
		(sheetname "/DDR3/")
		(sheetfile "ddr3.kicad_sch")
		(attr smd)
		(fp_rect
			(start -0.925 0.47)
			(end 0.925 -0.47)
			(stroke
				(width 0.05)
				(type default)
			)
			(fill no)
			(layer "B.CrtYd")
		)
		(fp_line
			(start 0.504 -0.248)
			(end -0.494 -0.248)
			(stroke
				(width 0.15)
				(type solid)
			)
			(layer "B.Fab")
		)
		(fp_line
			(start -0.494 -0.248)
			(end -0.494 0.25)
			(stroke
				(width 0.15)
				(type solid)
			)
			(layer "B.Fab")
		)
		(fp_line
			(start 0.504 0.25)
			(end 0.504 -0.248)
			(stroke
				(width 0.15)
				(type solid)
			)
			(layer "B.Fab")
		)
		(fp_line
			(start -0.494 0.25)
			(end 0.504 0.25)
			(stroke
				(width 0.15)
				(type solid)
			)
			(layer "B.Fab")
		)
		(pad "1" smd roundrect
			(at -0.48 0 90)
			(size 0.59 0.64)
			(layers "B.Cu" "B.Mask" "B.Paste")
			(roundrect_rratio 0.25)
			(net 1 "GND")
			(pintype "passive")
		)
		(pad "2" smd roundrect
			(at 0.48 0 90)
			(size 0.59 0.64)
			(layers "B.Cu" "B.Mask" "B.Paste")
			(roundrect_rratio 0.25)
			(net 143 "/DDR3/DDR3_VTT")
			(pintype "passive")
		)
	)
	(footprint "antmicro-footprints:C_0402_1005Metric"
		(layer "B.Cu")
		(at 98.57 87.005 90)
		(descr "Capacitor SMD 0402")
		(tags "capacitor SMD 0402")
		(property "Reference" "C228"
			(at 1.005 -1.07 90)
			(layer "B.SilkS")
			(effects
				(font
					(size 0.7 0.7)
					(thickness 0.15)
				)
				(justify right bottom mirror)
			)
		)
		(property "Value" "C_100n_0402"
			(at 0 -1.4 90)
			(layer "B.Fab")
			(effects
				(font
					(size 0.7 0.7)
					(thickness 0.15)
				)
				(justify right bottom mirror)
			)
		)
		(property "Datasheet" "https://www.murata.com/products/productdetail?partno=GRM155R61H104KE14%23"
			(at 0 0 90)
			(layer "F.Fab")
			(hide yes)
			(effects
				(font
					(size 1.27 1.27)
					(thickness 0.15)
				)
			)
		)
		(property "Description" "SMD Multilayer Ceramic Capacitor, 0.1 µF, 50 V, 0402 [1005 Metric], ± 10%, X5R, GRM Series"
			(at 0 0 90)
			(layer "F.Fab")
			(hide yes)
			(effects
				(font
					(size 1.27 1.27)
					(thickness 0.15)
				)
			)
		)
		(property "Author" "Antmicro"
			(at 185.575 -11.565 0)
			(layer "B.Fab")
			(hide yes)
			(effects
				(font
					(size 1 1)
					(thickness 0.15)
				)
				(justify mirror)
			)
		)
		(property "Dielectric" "X5R"
			(at 185.575 -11.565 0)
			(layer "B.Fab")
			(hide yes)
			(effects
				(font
					(size 1 1)
					(thickness 0.15)
				)
				(justify mirror)
			)
		)
		(property "License" "Apache-2.0"
			(at 185.575 -11.565 0)
			(layer "B.Fab")
			(hide yes)
			(effects
				(font
					(size 1 1)
					(thickness 0.15)
				)
				(justify mirror)
			)
		)
		(property "MPN" "GRM155R61H104KE14D"
			(at 185.575 -11.565 0)
			(layer "B.Fab")
			(hide yes)
			(effects
				(font
					(size 1 1)
					(thickness 0.15)
				)
				(justify mirror)
			)
		)
		(property "Manufacturer" "Murata"
			(at 185.575 -11.565 0)
			(layer "B.Fab")
			(hide yes)
			(effects
				(font
					(size 1 1)
					(thickness 0.15)
				)
				(justify mirror)
			)
		)
		(property "Val" "100n"
			(at 185.575 -11.565 0)
			(layer "B.Fab")
			(hide yes)
			(effects
				(font
					(size 1 1)
					(thickness 0.15)
				)
				(justify mirror)
			)
		)
		(property "Voltage" "50V"
			(at 185.575 -11.565 0)
			(layer "B.Fab")
			(hide yes)
			(effects
				(font
					(size 1 1)
					(thickness 0.15)
				)
				(justify mirror)
			)
		)
		(sheetname "/Ethernet/")
		(sheetfile "ethernet.kicad_sch")
		(attr smd)
		(fp_rect
			(start -0.925 0.47)
			(end 0.925 -0.47)
			(stroke
				(width 0.05)
				(type default)
			)
			(fill no)
			(layer "B.CrtYd")
		)
		(fp_line
			(start 0.504 -0.248)
			(end -0.494 -0.248)
			(stroke
				(width 0.15)
				(type solid)
			)
			(layer "B.Fab")
		)
		(fp_line
			(start -0.494 -0.248)
			(end -0.494 0.25)
			(stroke
				(width 0.15)
				(type solid)
			)
			(layer "B.Fab")
		)
		(fp_line
			(start 0.504 0.25)
			(end 0.504 -0.248)
			(stroke
				(width 0.15)
				(type solid)
			)
			(layer "B.Fab")
		)
		(fp_line
			(start -0.494 0.25)
			(end 0.504 0.25)
			(stroke
				(width 0.15)
				(type solid)
			)
			(layer "B.Fab")
		)
		(pad "1" smd roundrect
			(at -0.48 0 90)
			(size 0.59 0.64)
			(layers "B.Cu" "B.Mask" "B.Paste")
			(roundrect_rratio 0.25)
			(net 1 "GND")
			(pintype "passive")
		)
		(pad "2" smd roundrect
			(at 0.48 0 90)
			(size 0.59 0.64)
			(layers "B.Cu" "B.Mask" "B.Paste")
			(roundrect_rratio 0.25)
			(net 206 "Net-(J1-TRCT4)")
			(pintype "passive")
		)
	)
	(footprint "antmicro-footprints:R_0402_1005Metric"
		(layer "B.Cu")
		(at 70.967 91.556 -90)
		(descr "Resistor SMD 0402")
		(tags "resistor SMD 0402")
		(property "Reference" "R63"
			(at 1.884 -0.483 90)
			(layer "B.SilkS")
			(effects
				(font
					(size 0.7 0.7)
					(thickness 0.15)
				)
				(justify left bottom mirror)
			)
		)
		(property "Value" "R_100k_0402"
			(at 0 -1.4 90)
			(layer "B.Fab")
			(effects
				(font
					(size 0.7 0.7)
					(thickness 0.15)
				)
				(justify left bottom mirror)
			)
		)
		(property "Datasheet" "https://www.bourns.com/docs/product-datasheets/cr.pdf"
			(at 0 0 270)
			(layer "F.Fab")
			(hide yes)
			(effects
				(font
					(size 1.27 1.27)
					(thickness 0.15)
				)
			)
		)
		(property "Description" "SMD Chip Resistor, 100 kohm, ± 1%, 62.5 mW, 0402 [1005 Metric], Thick Film, General Purpose"
			(at 0 0 270)
			(layer "F.Fab")
			(hide yes)
			(effects
				(font
					(size 1.27 1.27)
					(thickness 0.15)
				)
			)
		)
		(property "Author" "Antmicro"
			(at -20.589 162.523 0)
			(layer "B.Fab")
			(hide yes)
			(effects
				(font
					(size 1 1)
					(thickness 0.15)
				)
				(justify mirror)
			)
		)
		(property "License" "Apache-2.0"
			(at -20.589 162.523 0)
			(layer "B.Fab")
			(hide yes)
			(effects
				(font
					(size 1 1)
					(thickness 0.15)
				)
				(justify mirror)
			)
		)
		(property "MPN" "CR0402-FX-1003GLF"
			(at -20.589 162.523 0)
			(layer "B.Fab")
			(hide yes)
			(effects
				(font
					(size 1 1)
					(thickness 0.15)
				)
				(justify mirror)
			)
		)
		(property "Manufacturer" "Bourns"
			(at -20.589 162.523 0)
			(layer "B.Fab")
			(hide yes)
			(effects
				(font
					(size 1 1)
					(thickness 0.15)
				)
				(justify mirror)
			)
		)
		(property "Tolerance" "1%"
			(at -20.589 162.523 0)
			(layer "B.Fab")
			(hide yes)
			(effects
				(font
					(size 1 1)
					(thickness 0.15)
				)
				(justify mirror)
			)
		)
		(property "Val" "100k"
			(at -20.589 162.523 0)
			(layer "B.Fab")
			(hide yes)
			(effects
				(font
					(size 1 1)
					(thickness 0.15)
				)
				(justify mirror)
			)
		)
		(sheetname "/Power supply/")
		(sheetfile "power-supply.kicad_sch")
		(attr smd)
		(fp_rect
			(start -0.925 0.47)
			(end 0.925 -0.47)
			(stroke
				(width 0.05)
				(type default)
			)
			(fill no)
			(layer "B.CrtYd")
		)
		(fp_rect
			(start -0.5 0.25)
			(end 0.5 -0.25)
			(stroke
				(width 0.15)
				(type solid)
			)
			(fill no)
			(layer "B.Fab")
		)
		(pad "1" smd roundrect
			(at -0.48 0 270)
			(size 0.59 0.64)
			(layers "B.Cu" "B.Mask" "B.Paste")
			(roundrect_rratio 0.25)
			(net 4 "VCC5V0")
			(pintype "passive")
		)
		(pad "2" smd roundrect
			(at 0.48 0 270)
			(size 0.59 0.64)
			(layers "B.Cu" "B.Mask" "B.Paste")
			(roundrect_rratio 0.25)
			(net 295 "/Power supply/VCCINT_EN")
			(pintype "passive")
		)
	)
	(footprint "antmicro-footprints:R_0402_1005Metric"
		(layer "B.Cu")
		(at 69.967 91.556 -90)
		(descr "Resistor SMD 0402")
		(tags "resistor SMD 0402")
		(property "Reference" "R64"
			(at 1.884 -0.393 90)
			(layer "B.SilkS")
			(effects
				(font
					(size 0.7 0.7)
					(thickness 0.15)
				)
				(justify left bottom mirror)
			)
		)
		(property "Value" "R_100k_0402"
			(at 0 -1.4 90)
			(layer "B.Fab")
			(effects
				(font
					(size 0.7 0.7)
					(thickness 0.15)
				)
				(justify left bottom mirror)
			)
		)
		(property "Datasheet" "https://www.bourns.com/docs/product-datasheets/cr.pdf"
			(at 0 0 270)
			(layer "F.Fab")
			(hide yes)
			(effects
				(font
					(size 1.27 1.27)
					(thickness 0.15)
				)
			)
		)
		(property "Description" "SMD Chip Resistor, 100 kohm, ± 1%, 62.5 mW, 0402 [1005 Metric], Thick Film, General Purpose"
			(at 0 0 270)
			(layer "F.Fab")
			(hide yes)
			(effects
				(font
					(size 1.27 1.27)
					(thickness 0.15)
				)
			)
		)
		(property "Author" "Antmicro"
			(at -21.589 161.523 0)
			(layer "B.Fab")
			(hide yes)
			(effects
				(font
					(size 1 1)
					(thickness 0.15)
				)
				(justify mirror)
			)
		)
		(property "License" "Apache-2.0"
			(at -21.589 161.523 0)
			(layer "B.Fab")
			(hide yes)
			(effects
				(font
					(size 1 1)
					(thickness 0.15)
				)
				(justify mirror)
			)
		)
		(property "MPN" "CR0402-FX-1003GLF"
			(at -21.589 161.523 0)
			(layer "B.Fab")
			(hide yes)
			(effects
				(font
					(size 1 1)
					(thickness 0.15)
				)
				(justify mirror)
			)
		)
		(property "Manufacturer" "Bourns"
			(at -21.589 161.523 0)
			(layer "B.Fab")
			(hide yes)
			(effects
				(font
					(size 1 1)
					(thickness 0.15)
				)
				(justify mirror)
			)
		)
		(property "Tolerance" "1%"
			(at -21.589 161.523 0)
			(layer "B.Fab")
			(hide yes)
			(effects
				(font
					(size 1 1)
					(thickness 0.15)
				)
				(justify mirror)
			)
		)
		(property "Val" "100k"
			(at -21.589 161.523 0)
			(layer "B.Fab")
			(hide yes)
			(effects
				(font
					(size 1 1)
					(thickness 0.15)
				)
				(justify mirror)
			)
		)
		(sheetname "/Power supply/")
		(sheetfile "power-supply.kicad_sch")
		(attr smd)
		(fp_rect
			(start -0.925 0.47)
			(end 0.925 -0.47)
			(stroke
				(width 0.05)
				(type default)
			)
			(fill no)
			(layer "B.CrtYd")
		)
		(fp_rect
			(start -0.5 0.25)
			(end 0.5 -0.25)
			(stroke
				(width 0.15)
				(type solid)
			)
			(fill no)
			(layer "B.Fab")
		)
		(pad "1" smd roundrect
			(at -0.48 0 270)
			(size 0.59 0.64)
			(layers "B.Cu" "B.Mask" "B.Paste")
			(roundrect_rratio 0.25)
			(net 4 "VCC5V0")
			(pintype "passive")
		)
		(pad "2" smd roundrect
			(at 0.48 0 270)
			(size 0.59 0.64)
			(layers "B.Cu" "B.Mask" "B.Paste")
			(roundrect_rratio 0.25)
			(net 296 "/Power supply/VCCAUX_EN")
			(pintype "passive")
		)
	)
)
